# T6G (Grand Teton) — schematic netlist excerpt (pin names and nets, part order shuffled) for the footprints in the layout excerpt that follows; sources: Cadence DE-HDL packaged netlist, KiCad conversion of 04192023_DAF0TMB3IC0_F0TG_MB_C_brd_V02_OCP.brd

PR216  Q_RES  0 5% CHIP  pkg 0402LF  page 216 : A = PVDDCR_SOC_P1_VOS3 ; B = PVDDCR_SOC_P1
C2453  Q_CAP  22UF 4V 20% X6S  pkg C0402  page 74 : A = PVDDCR_SOC_P1 ; B = GND
C1008  Q_CAP  0.1UF 10V 10% X7S  pkg C0201  page 312 : A = P0V9_CPU0_RT3_2A ; B = GND

(kicad_pcb
	(version 20260206)
	(generator "pcbnew")
	(generator_version "10.0")
	(general
		(thickness 1.6)
		(legacy_teardrops no)
	)
	(paper "A4")
	(title_block
		(title "04192023_DAF0TMB3IC0_F0TG_MB_C_brd_V02_OCP.brd")
		(comment 1 "Grand Teton / footprints 6983-6985 of 8354")
	)
	(layers
		(0 "F.Cu" signal "TOP")
		(4 "In1.Cu" signal "GND")
		(6 "In2.Cu" signal "IN1")
		(8 "In3.Cu" signal "GND1")
		(10 "In4.Cu" signal "IN2")
		(12 "In5.Cu" signal "GND2")
		(14 "In6.Cu" signal "IN3")
		(16 "In7.Cu" signal "GND3")
		(18 "In8.Cu" signal "VCC")
		(20 "In9.Cu" signal "VCC1")
		(22 "In10.Cu" signal "GND4")
		(24 "In11.Cu" signal "IN4")
		(26 "In12.Cu" signal "GND5")
		(28 "In13.Cu" signal "IN5")
		(30 "In14.Cu" signal "GND6")
		(32 "In15.Cu" signal "IN6")
		(34 "In16.Cu" signal "GND7")
		(2 "B.Cu" signal "BOTTOM")
		(9 "F.Adhes" user "F.Adhesive")
		(11 "B.Adhes" user "B.Adhesive")
		(13 "F.Paste" user "Package Geometry/Pastemask Top")
		(15 "B.Paste" user "Package Geometry/Pastemask Bottom")
		(5 "F.SilkS" user "Ref Des/Silkscreen Top")
		(7 "B.SilkS" user "Ref Des/Silkscreen Bottom")
		(1 "F.Mask" user "Board Geometry/Soldermask Top")
		(3 "B.Mask" user "Board Geometry/Soldermask Bottom")
		(17 "Dwgs.User" user "User.Drawings")
		(19 "Cmts.User" user "User.Comments")
		(21 "Eco1.User" user "User.Eco1")
		(23 "Eco2.User" user "User.Eco2")
		(25 "Edge.Cuts" user "Board Geometry/Outline")
		(27 "Margin" user)
		(31 "F.CrtYd" user "Package Geometry/Place Bound Top")
		(29 "B.CrtYd" user "Package Geometry/Place Bound Bottom")
		(35 "F.Fab" user "Ref Des/Assembly Top")
		(33 "B.Fab" user "Ref Des/Assembly Bottom")
	)
	(footprint ""
		(layer "B.Cu")
		(at 136.08558 -153.865834 90)
		(property "Reference" "PR216"
			(at 0 0 90)
			(layer "B.SilkS")
			(hide yes)
			(effects
				(font
					(size 1.27 1.27)
				)
				(justify mirror)
			)
		)
		(property "Value" ""
			(at 0 0 90)
			(layer "B.Fab")
			(effects
				(font
					(size 1.27 1.27)
				)
				(justify mirror)
			)
		)
		(duplicate_pad_numbers_are_jumpers no)
		(fp_line
			(start 0.7874 -0.4064)
			(end -0.7874 -0.4064)
			(stroke
				(width 0.1524)
				(type default)
			)
			(layer "B.SilkS")
		)
		(fp_line
			(start -0.7874 -0.4064)
			(end -0.7874 0.4064)
			(stroke
				(width 0.1524)
				(type default)
			)
			(layer "B.SilkS")
		)
		(fp_line
			(start 0.7874 0.4064)
			(end 0.7874 -0.4064)
			(stroke
				(width 0.1524)
				(type default)
			)
			(layer "B.SilkS")
		)
		(fp_line
			(start -0.7874 0.4064)
			(end 0.7874 0.4064)
			(stroke
				(width 0.1524)
				(type default)
			)
			(layer "B.SilkS")
		)
		(fp_line
			(start 0.67945 -0.305054)
			(end 0.12065 -0.305054)
			(stroke
				(width 0.1)
				(type default)
			)
			(layer "B.Fab")
		)
		(fp_line
			(start 0.12065 -0.305054)
			(end 0.12065 -0.2794)
			(stroke
				(width 0.1)
				(type default)
			)
			(layer "B.Fab")
		)
		(fp_line
			(start -0.12065 -0.3048)
			(end -0.67945 -0.3048)
			(stroke
				(width 0.1)
				(type default)
			)
			(layer "B.Fab")
		)
		(fp_line
			(start -0.67945 -0.3048)
			(end -0.67945 0.3048)
			(stroke
				(width 0.1)
				(type default)
			)
			(layer "B.Fab")
		)
		(fp_line
			(start 0.12065 -0.2794)
			(end -0.12065 -0.2794)
			(stroke
				(width 0.1)
				(type default)
			)
			(layer "B.Fab")
		)
		(fp_line
			(start -0.12065 -0.2794)
			(end -0.12065 -0.3048)
			(stroke
				(width 0.1)
				(type default)
			)
			(layer "B.Fab")
		)
		(fp_line
			(start 0.12065 0.2794)
			(end 0.12065 0.3048)
			(stroke
				(width 0.1)
				(type default)
			)
			(layer "B.Fab")
		)
		(fp_line
			(start -0.120396 0.2794)
			(end 0.12065 0.2794)
			(stroke
				(width 0.1)
				(type default)
			)
			(layer "B.Fab")
		)
		(fp_line
			(start 0.67945 0.3048)
			(end 0.67945 -0.305054)
			(stroke
				(width 0.1)
				(type default)
			)
			(layer "B.Fab")
		)
		(fp_line
			(start 0.12065 0.3048)
			(end 0.67945 0.3048)
			(stroke
				(width 0.1)
				(type default)
			)
			(layer "B.Fab")
		)
		(fp_line
			(start -0.120396 0.3048)
			(end -0.120396 0.2794)
			(stroke
				(width 0.1)
				(type default)
			)
			(layer "B.Fab")
		)
		(fp_line
			(start -0.67945 0.3048)
			(end -0.120396 0.3048)
			(stroke
				(width 0.1)
				(type default)
			)
			(layer "B.Fab")
		)
		(pad "1" smd circle
			(at 0.40005 0 270)
			(size 0 0)
			(layers "B.Cu" "B.Mask" "B.Paste")
			(net "PVDDCR_SOC_P1_VOS3")
		)
		(pad "2" smd circle
			(at -0.40005 0 270)
			(size 0 0)
			(layers "B.Cu" "B.Mask" "B.Paste")
			(net "PVDDCR_SOC_P1")
		)
	)
	(footprint ""
		(layer "B.Cu")
		(at 103.799386 -255.845564 180)
		(property "Reference" "C2453"
			(at 0 0 0)
			(layer "B.SilkS")
			(hide yes)
			(effects
				(font
					(size 1.27 1.27)
				)
				(justify mirror)
			)
		)
		(property "Value" ""
			(at 0 0 0)
			(layer "B.Fab")
			(effects
				(font
					(size 1.27 1.27)
				)
				(justify mirror)
			)
		)
		(duplicate_pad_numbers_are_jumpers no)
		(fp_line
			(start 0.7874 0.4064)
			(end 0.7874 -0.4064)
			(stroke
				(width 0.1524)
				(type default)
			)
			(layer "B.SilkS")
		)
		(fp_line
			(start 0.7874 -0.4064)
			(end -0.7874 -0.4064)
			(stroke
				(width 0.1524)
				(type default)
			)
			(layer "B.SilkS")
		)
		(fp_line
			(start -0.7874 0.4064)
			(end 0.7874 0.4064)
			(stroke
				(width 0.1524)
				(type default)
			)
			(layer "B.SilkS")
		)
		(fp_line
			(start -0.7874 -0.4064)
			(end -0.7874 0.4064)
			(stroke
				(width 0.1524)
				(type default)
			)
			(layer "B.SilkS")
		)
		(fp_line
			(start 0.67945 0.3048)
			(end 0.67945 -0.305054)
			(stroke
				(width 0.1)
				(type default)
			)
			(layer "B.Fab")
		)
		(fp_line
			(start 0.67945 -0.305054)
			(end 0.12065 -0.305054)
			(stroke
				(width 0.1)
				(type default)
			)
			(layer "B.Fab")
		)
		(fp_line
			(start 0.12065 0.3048)
			(end 0.67945 0.3048)
			(stroke
				(width 0.1)
				(type default)
			)
			(layer "B.Fab")
		)
		(fp_line
			(start 0.12065 0.2794)
			(end 0.12065 0.3048)
			(stroke
				(width 0.1)
				(type default)
			)
			(layer "B.Fab")
		)
		(fp_line
			(start 0.12065 -0.2794)
			(end -0.12065 -0.2794)
			(stroke
				(width 0.1)
				(type default)
			)
			(layer "B.Fab")
		)
		(fp_line
			(start 0.12065 -0.305054)
			(end 0.12065 -0.2794)
			(stroke
				(width 0.1)
				(type default)
			)
			(layer "B.Fab")
		)
		(fp_line
			(start -0.120396 0.3048)
			(end -0.120396 0.2794)
			(stroke
				(width 0.1)
				(type default)
			)
			(layer "B.Fab")
		)
		(fp_line
			(start -0.120396 0.2794)
			(end 0.12065 0.2794)
			(stroke
				(width 0.1)
				(type default)
			)
			(layer "B.Fab")
		)
		(fp_line
			(start -0.12065 -0.2794)
			(end -0.12065 -0.3048)
			(stroke
				(width 0.1)
				(type default)
			)
			(layer "B.Fab")
		)
		(fp_line
			(start -0.12065 -0.3048)
			(end -0.67945 -0.3048)
			(stroke
				(width 0.1)
				(type default)
			)
			(layer "B.Fab")
		)
		(fp_line
			(start -0.67945 0.3048)
			(end -0.120396 0.3048)
			(stroke
				(width 0.1)
				(type default)
			)
			(layer "B.Fab")
		)
		(fp_line
			(start -0.67945 -0.3048)
			(end -0.67945 0.3048)
			(stroke
				(width 0.1)
				(type default)
			)
			(layer "B.Fab")
		)
		(pad "1" smd circle
			(at 0.40005 0)
			(size 0 0)
			(layers "B.Cu" "B.Mask" "B.Paste")
			(net "PVDDCR_SOC_P1")
		)
		(pad "2" smd circle
			(at -0.40005 0)
			(size 0 0)
			(layers "B.Cu" "B.Mask" "B.Paste")
			(net "GND")
		)
	)
	(footprint ""
		(layer "B.Cu")
		(at 371.818408 -396.393162 -90)
		(property "Reference" "C1008"
			(at 0 0 90)
			(layer "B.SilkS")
			(hide yes)
			(effects
				(font
					(size 1.27 1.27)
				)
				(justify mirror)
			)
		)
		(property "Value" ""
			(at 0 0 90)
			(layer "B.Fab")
			(effects
				(font
					(size 1.27 1.27)
				)
				(justify mirror)
			)
		)
		(duplicate_pad_numbers_are_jumpers no)
		(fp_line
			(start -0.299974 0.150114)
			(end 0.299974 0.150114)
			(stroke
				(width 0.1)
				(type default)
			)
			(layer "B.Fab")
		)
		(fp_line
			(start 0.299974 0.150114)
			(end 0.299974 -0.150114)
			(stroke
				(width 0.1)
				(type default)
			)
			(layer "B.Fab")
		)
		(fp_line
			(start -0.299974 -0.150114)
			(end -0.299974 0.150114)
			(stroke
				(width 0.1)
				(type default)
			)
			(layer "B.Fab")
		)
		(fp_line
			(start 0.299974 -0.150114)
			(end -0.299974 -0.150114)
			(stroke
				(width 0.1)
				(type default)
			)
			(layer "B.Fab")
		)
		(pad "1" smd rect
			(at 0.2667 0 90)
			(size 0.3048 0.381)
			(layers "B.Cu" "B.Mask" "B.Paste")
			(net "P0V9_CPU0_RT3_2A")
		)
		(pad "2" smd rect
			(at -0.2667 0 90)
			(size 0.3048 0.381)
			(layers "B.Cu" "B.Mask" "B.Paste")
			(net "GND")
		)
	)
)
